# T6G (Grand Teton) — schematic netlist excerpt (pin names and nets, part order shuffled) for the footprints in the layout excerpt that follows; sources: Cadence DE-HDL packaged netlist, KiCad conversion of 04192023_DAF0TMB3IC0_F0TG_MB_C_brd_V02_OCP.brd

R1052  Q_RES  1K 1% EMPTY  pkg 0402LF  page 169 : A = P3V3_AUX ; B = P3V3_AUX_DSC_G1
C1519  Q_CAP  0.1UF 16V 10% X7R  pkg C0402  page 174 : A = PVDD18_S5_P0 ; B = GND

(kicad_pcb
	(version 20260206)
	(generator "pcbnew")
	(generator_version "10.0")
	(general
		(thickness 1.6)
		(legacy_teardrops no)
	)
	(paper "A4")
	(title_block
		(title "04192023_DAF0TMB3IC0_F0TG_MB_C_brd_V02_OCP.brd")
		(comment 1 "Grand Teton / footprints 4089-4090 of 8354")
	)
	(layers
		(0 "F.Cu" signal "TOP")
		(4 "In1.Cu" signal "GND")
		(6 "In2.Cu" signal "IN1")
		(8 "In3.Cu" signal "GND1")
		(10 "In4.Cu" signal "IN2")
		(12 "In5.Cu" signal "GND2")
		(14 "In6.Cu" signal "IN3")
		(16 "In7.Cu" signal "GND3")
		(18 "In8.Cu" signal "VCC")
		(20 "In9.Cu" signal "VCC1")
		(22 "In10.Cu" signal "GND4")
		(24 "In11.Cu" signal "IN4")
		(26 "In12.Cu" signal "GND5")
		(28 "In13.Cu" signal "IN5")
		(30 "In14.Cu" signal "GND6")
		(32 "In15.Cu" signal "IN6")
		(34 "In16.Cu" signal "GND7")
		(2 "B.Cu" signal "BOTTOM")
		(9 "F.Adhes" user "F.Adhesive")
		(11 "B.Adhes" user "B.Adhesive")
		(13 "F.Paste" user "Package Geometry/Pastemask Top")
		(15 "B.Paste" user "Package Geometry/Pastemask Bottom")
		(5 "F.SilkS" user "Ref Des/Silkscreen Top")
		(7 "B.SilkS" user "Ref Des/Silkscreen Bottom")
		(1 "F.Mask" user "Board Geometry/Soldermask Top")
		(3 "B.Mask" user "Board Geometry/Soldermask Bottom")
		(17 "Dwgs.User" user "User.Drawings")
		(19 "Cmts.User" user "User.Comments")
		(21 "Eco1.User" user "User.Eco1")
		(23 "Eco2.User" user "User.Eco2")
		(25 "Edge.Cuts" user "Board Geometry/Outline")
		(27 "Margin" user)
		(31 "F.CrtYd" user "Package Geometry/Place Bound Top")
		(29 "B.CrtYd" user "Package Geometry/Place Bound Bottom")
		(35 "F.Fab" user "Ref Des/Assembly Top")
		(33 "B.Fab" user "Ref Des/Assembly Bottom")
	)
	(footprint ""
		(layer "F.Cu")
		(at 230.675688 -147.932648 180)
		(property "Reference" "C1519"
			(at 0 0 180)
			(layer "F.SilkS")
			(hide yes)
			(effects
				(font
					(size 1.27 1.27)
				)
			)
		)
		(property "Value" ""
			(at 0 0 180)
			(layer "F.Fab")
			(effects
				(font
					(size 1.27 1.27)
				)
			)
		)
		(duplicate_pad_numbers_are_jumpers no)
		(fp_line
			(start 0.7874 0.4064)
			(end -0.7874 0.4064)
			(stroke
				(width 0.1524)
				(type default)
			)
			(layer "F.SilkS")
		)
		(fp_line
			(start 0.7874 -0.4064)
			(end 0.7874 0.4064)
			(stroke
				(width 0.1524)
				(type default)
			)
			(layer "F.SilkS")
		)
		(fp_line
			(start -0.7874 0.4064)
			(end -0.7874 -0.4064)
			(stroke
				(width 0.1524)
				(type default)
			)
			(layer "F.SilkS")
		)
		(fp_line
			(start -0.7874 -0.4064)
			(end 0.7874 -0.4064)
			(stroke
				(width 0.1524)
				(type default)
			)
			(layer "F.SilkS")
		)
		(fp_line
			(start 0.67945 0.3048)
			(end 0.120396 0.3048)
			(stroke
				(width 0.1)
				(type default)
			)
			(layer "F.Fab")
		)
		(fp_line
			(start 0.67945 -0.3048)
			(end 0.67945 0.3048)
			(stroke
				(width 0.1)
				(type default)
			)
			(layer "F.Fab")
		)
		(fp_line
			(start 0.12065 -0.2794)
			(end 0.12065 -0.3048)
			(stroke
				(width 0.1)
				(type default)
			)
			(layer "F.Fab")
		)
		(fp_line
			(start 0.12065 -0.3048)
			(end 0.67945 -0.3048)
			(stroke
				(width 0.1)
				(type default)
			)
			(layer "F.Fab")
		)
		(fp_line
			(start 0.120396 0.3048)
			(end 0.120396 0.2794)
			(stroke
				(width 0.1)
				(type default)
			)
			(layer "F.Fab")
		)
		(fp_line
			(start 0.120396 0.2794)
			(end -0.12065 0.2794)
			(stroke
				(width 0.1)
				(type default)
			)
			(layer "F.Fab")
		)
		(fp_line
			(start -0.12065 0.3048)
			(end -0.67945 0.3048)
			(stroke
				(width 0.1)
				(type default)
			)
			(layer "F.Fab")
		)
		(fp_line
			(start -0.12065 0.2794)
			(end -0.12065 0.3048)
			(stroke
				(width 0.1)
				(type default)
			)
			(layer "F.Fab")
		)
		(fp_line
			(start -0.12065 -0.2794)
			(end 0.12065 -0.2794)
			(stroke
				(width 0.1)
				(type default)
			)
			(layer "F.Fab")
		)
		(fp_line
			(start -0.12065 -0.305054)
			(end -0.12065 -0.2794)
			(stroke
				(width 0.1)
				(type default)
			)
			(layer "F.Fab")
		)
		(fp_line
			(start -0.67945 0.3048)
			(end -0.67945 -0.305054)
			(stroke
				(width 0.1)
				(type default)
			)
			(layer "F.Fab")
		)
		(fp_line
			(start -0.67945 -0.305054)
			(end -0.12065 -0.305054)
			(stroke
				(width 0.1)
				(type default)
			)
			(layer "F.Fab")
		)
		(pad "1" smd circle
			(at -0.40005 0 180)
			(size 0 0)
			(layers "F.Cu" "F.Mask" "F.Paste")
			(net "PVDD18_S5_P0")
		)
		(pad "2" smd circle
			(at 0.40005 0 180)
			(size 0 0)
			(layers "F.Cu" "F.Mask" "F.Paste")
			(net "GND")
		)
	)
	(footprint ""
		(layer "F.Cu")
		(at 44.7294 -104.7369)
		(property "Reference" "R1052"
			(at 0 0 0)
			(layer "F.SilkS")
			(hide yes)
			(effects
				(font
					(size 1.27 1.27)
				)
			)
		)
		(property "Value" ""
			(at 0 0 0)
			(layer "F.Fab")
			(effects
				(font
					(size 1.27 1.27)
				)
			)
		)
		(duplicate_pad_numbers_are_jumpers no)
		(fp_line
			(start -0.7874 -0.4064)
			(end 0.7874 -0.4064)
			(stroke
				(width 0.1524)
				(type default)
			)
			(layer "F.SilkS")
		)
		(fp_line
			(start -0.7874 0.4064)
			(end -0.7874 -0.4064)
			(stroke
				(width 0.1524)
				(type default)
			)
			(layer "F.SilkS")
		)
		(fp_line
			(start 0.7874 -0.4064)
			(end 0.7874 0.4064)
			(stroke
				(width 0.1524)
				(type default)
			)
			(layer "F.SilkS")
		)
		(fp_line
			(start 0.7874 0.4064)
			(end -0.7874 0.4064)
			(stroke
				(width 0.1524)
				(type default)
			)
			(layer "F.SilkS")
		)
		(fp_line
			(start -0.67945 -0.305054)
			(end -0.12065 -0.305054)
			(stroke
				(width 0.1)
				(type default)
			)
			(layer "F.Fab")
		)
		(fp_line
			(start -0.67945 0.3048)
			(end -0.67945 -0.305054)
			(stroke
				(width 0.1)
				(type default)
			)
			(layer "F.Fab")
		)
		(fp_line
			(start -0.12065 -0.305054)
			(end -0.12065 -0.2794)
			(stroke
				(width 0.1)
				(type default)
			)
			(layer "F.Fab")
		)
		(fp_line
			(start -0.12065 -0.2794)
			(end 0.12065 -0.2794)
			(stroke
				(width 0.1)
				(type default)
			)
			(layer "F.Fab")
		)
		(fp_line
			(start -0.12065 0.2794)
			(end -0.12065 0.3048)
			(stroke
				(width 0.1)
				(type default)
			)
			(layer "F.Fab")
		)
		(fp_line
			(start -0.12065 0.3048)
			(end -0.67945 0.3048)
			(stroke
				(width 0.1)
				(type default)
			)
			(layer "F.Fab")
		)
		(fp_line
			(start 0.120396 0.2794)
			(end -0.12065 0.2794)
			(stroke
				(width 0.1)
				(type default)
			)
			(layer "F.Fab")
		)
		(fp_line
			(start 0.120396 0.3048)
			(end 0.120396 0.2794)
			(stroke
				(width 0.1)
				(type default)
			)
			(layer "F.Fab")
		)
		(fp_line
			(start 0.12065 -0.3048)
			(end 0.67945 -0.3048)
			(stroke
				(width 0.1)
				(type default)
			)
			(layer "F.Fab")
		)
		(fp_line
			(start 0.12065 -0.2794)
			(end 0.12065 -0.3048)
			(stroke
				(width 0.1)
				(type default)
			)
			(layer "F.Fab")
		)
		(fp_line
			(start 0.67945 -0.3048)
			(end 0.67945 0.3048)
			(stroke
				(width 0.1)
				(type default)
			)
			(layer "F.Fab")
		)
		(fp_line
			(start 0.67945 0.3048)
			(end 0.120396 0.3048)
			(stroke
				(width 0.1)
				(type default)
			)
			(layer "F.Fab")
		)
		(pad "1" smd circle
			(at -0.40005 0)
			(size 0 0)
			(layers "F.Cu" "F.Mask" "F.Paste")
			(net "P3V3_AUX")
		)
		(pad "2" smd circle
			(at 0.40005 0)
			(size 0 0)
			(layers "F.Cu" "F.Mask" "F.Paste")
			(net "P3V3_AUX_DSC_G1")
		)
	)
)
